# T6G (Grand Teton) — schematic netlist excerpt (pin names and nets, part order shuffled) for the footprints in the layout excerpt that follows; sources: Cadence DE-HDL packaged netlist, KiCad conversion of 04192023_DAF0TMB3IC0_F0TG_MB_C_brd_V02_OCP.brd

PR6618  Q_RES  0 5% CHIP  pkg 0402LF  page 362 : A = P0V9_RETIMER_CPU0_TEMP1_R ; B = GND
C1238  Q_CAP  0.1UF 25V 10% X7R  pkg 0402  page 131 : A = P3V3_OCP_SFF ; B = GND
C6756  Q_CAP_DIFFBUS  DIFF BUS_0.22UF 6.3V 20% X6S  pkg C0201  page 352 : \1\ = P5E_CPU1_P3_TX_BUF_C_DN<15> ; \2\ = P5E_CPU1_P3_TX_BUF_DN<15>

(kicad_pcb
	(version 20260206)
	(generator "pcbnew")
	(generator_version "10.0")
	(general
		(thickness 1.6)
		(legacy_teardrops no)
	)
	(paper "A4")
	(title_block
		(title "04192023_DAF0TMB3IC0_F0TG_MB_C_brd_V02_OCP.brd")
		(comment 1 "Grand Teton / footprints 5934-5936 of 8354")
	)
	(layers
		(0 "F.Cu" signal "TOP")
		(4 "In1.Cu" signal "GND")
		(6 "In2.Cu" signal "IN1")
		(8 "In3.Cu" signal "GND1")
		(10 "In4.Cu" signal "IN2")
		(12 "In5.Cu" signal "GND2")
		(14 "In6.Cu" signal "IN3")
		(16 "In7.Cu" signal "GND3")
		(18 "In8.Cu" signal "VCC")
		(20 "In9.Cu" signal "VCC1")
		(22 "In10.Cu" signal "GND4")
		(24 "In11.Cu" signal "IN4")
		(26 "In12.Cu" signal "GND5")
		(28 "In13.Cu" signal "IN5")
		(30 "In14.Cu" signal "GND6")
		(32 "In15.Cu" signal "IN6")
		(34 "In16.Cu" signal "GND7")
		(2 "B.Cu" signal "BOTTOM")
		(9 "F.Adhes" user "F.Adhesive")
		(11 "B.Adhes" user "B.Adhesive")
		(13 "F.Paste" user "Package Geometry/Pastemask Top")
		(15 "B.Paste" user "Package Geometry/Pastemask Bottom")
		(5 "F.SilkS" user "Ref Des/Silkscreen Top")
		(7 "B.SilkS" user "Ref Des/Silkscreen Bottom")
		(1 "F.Mask" user "Board Geometry/Soldermask Top")
		(3 "B.Mask" user "Board Geometry/Soldermask Bottom")
		(17 "Dwgs.User" user "User.Drawings")
		(19 "Cmts.User" user "User.Comments")
		(21 "Eco1.User" user "User.Eco1")
		(23 "Eco2.User" user "User.Eco2")
		(25 "Edge.Cuts" user "Board Geometry/Outline")
		(27 "Margin" user)
		(31 "F.CrtYd" user "Package Geometry/Place Bound Top")
		(29 "B.CrtYd" user "Package Geometry/Place Bound Bottom")
		(35 "F.Fab" user "Ref Des/Assembly Top")
		(33 "B.Fab" user "Ref Des/Assembly Bottom")
	)
	(footprint ""
		(layer "B.Cu")
		(at 435.549802 -12.104116 180)
		(property "Reference" "C1238"
			(at 0 0 0)
			(layer "B.SilkS")
			(hide yes)
			(effects
				(font
					(size 1.27 1.27)
				)
				(justify mirror)
			)
		)
		(property "Value" ""
			(at 0 0 0)
			(layer "B.Fab")
			(effects
				(font
					(size 1.27 1.27)
				)
				(justify mirror)
			)
		)
		(duplicate_pad_numbers_are_jumpers no)
		(fp_line
			(start 0.7874 0.4064)
			(end 0.7874 -0.4064)
			(stroke
				(width 0.1524)
				(type default)
			)
			(layer "B.SilkS")
		)
		(fp_line
			(start 0.7874 -0.4064)
			(end -0.7874 -0.4064)
			(stroke
				(width 0.1524)
				(type default)
			)
			(layer "B.SilkS")
		)
		(fp_line
			(start -0.7874 0.4064)
			(end 0.7874 0.4064)
			(stroke
				(width 0.1524)
				(type default)
			)
			(layer "B.SilkS")
		)
		(fp_line
			(start -0.7874 -0.4064)
			(end -0.7874 0.4064)
			(stroke
				(width 0.1524)
				(type default)
			)
			(layer "B.SilkS")
		)
		(fp_line
			(start 0.67945 0.3048)
			(end 0.67945 -0.305054)
			(stroke
				(width 0.1)
				(type default)
			)
			(layer "B.Fab")
		)
		(fp_line
			(start 0.67945 -0.305054)
			(end 0.12065 -0.305054)
			(stroke
				(width 0.1)
				(type default)
			)
			(layer "B.Fab")
		)
		(fp_line
			(start 0.12065 0.3048)
			(end 0.67945 0.3048)
			(stroke
				(width 0.1)
				(type default)
			)
			(layer "B.Fab")
		)
		(fp_line
			(start 0.12065 0.2794)
			(end 0.12065 0.3048)
			(stroke
				(width 0.1)
				(type default)
			)
			(layer "B.Fab")
		)
		(fp_line
			(start 0.12065 -0.2794)
			(end -0.12065 -0.2794)
			(stroke
				(width 0.1)
				(type default)
			)
			(layer "B.Fab")
		)
		(fp_line
			(start 0.12065 -0.305054)
			(end 0.12065 -0.2794)
			(stroke
				(width 0.1)
				(type default)
			)
			(layer "B.Fab")
		)
		(fp_line
			(start -0.120396 0.3048)
			(end -0.120396 0.2794)
			(stroke
				(width 0.1)
				(type default)
			)
			(layer "B.Fab")
		)
		(fp_line
			(start -0.120396 0.2794)
			(end 0.12065 0.2794)
			(stroke
				(width 0.1)
				(type default)
			)
			(layer "B.Fab")
		)
		(fp_line
			(start -0.12065 -0.2794)
			(end -0.12065 -0.3048)
			(stroke
				(width 0.1)
				(type default)
			)
			(layer "B.Fab")
		)
		(fp_line
			(start -0.12065 -0.3048)
			(end -0.67945 -0.3048)
			(stroke
				(width 0.1)
				(type default)
			)
			(layer "B.Fab")
		)
		(fp_line
			(start -0.67945 0.3048)
			(end -0.120396 0.3048)
			(stroke
				(width 0.1)
				(type default)
			)
			(layer "B.Fab")
		)
		(fp_line
			(start -0.67945 -0.3048)
			(end -0.67945 0.3048)
			(stroke
				(width 0.1)
				(type default)
			)
			(layer "B.Fab")
		)
		(pad "1" smd circle
			(at 0.40005 0)
			(size 0 0)
			(layers "B.Cu" "B.Mask" "B.Paste")
			(net "P3V3_OCP_SFF")
		)
		(pad "2" smd circle
			(at -0.40005 0)
			(size 0 0)
			(layers "B.Cu" "B.Mask" "B.Paste")
			(net "GND")
		)
	)
	(footprint ""
		(layer "B.Cu")
		(at 162.348926 -408.517344 90)
		(property "Reference" "C6756"
			(at 0 0 90)
			(layer "B.SilkS")
			(hide yes)
			(effects
				(font
					(size 1.27 1.27)
				)
				(justify mirror)
			)
		)
		(property "Value" ""
			(at 0 0 90)
			(layer "B.Fab")
			(effects
				(font
					(size 1.27 1.27)
				)
				(justify mirror)
			)
		)
		(duplicate_pad_numbers_are_jumpers no)
		(fp_line
			(start 0.299974 -0.150114)
			(end -0.299974 -0.150114)
			(stroke
				(width 0.1)
				(type default)
			)
			(layer "B.Fab")
		)
		(fp_line
			(start -0.299974 -0.150114)
			(end -0.299974 0.150114)
			(stroke
				(width 0.1)
				(type default)
			)
			(layer "B.Fab")
		)
		(fp_line
			(start 0.299974 0.150114)
			(end 0.299974 -0.150114)
			(stroke
				(width 0.1)
				(type default)
			)
			(layer "B.Fab")
		)
		(fp_line
			(start -0.299974 0.150114)
			(end 0.299974 0.150114)
			(stroke
				(width 0.1)
				(type default)
			)
			(layer "B.Fab")
		)
		(pad "1" smd rect
			(at 0.2667 0 270)
			(size 0.3048 0.381)
			(layers "B.Cu" "B.Mask" "B.Paste")
			(net "P5E_CPU1_P3_TX_BUF_C_DN<15>")
		)
		(pad "2" smd rect
			(at -0.2667 0 270)
			(size 0.3048 0.381)
			(layers "B.Cu" "B.Mask" "B.Paste")
			(net "P5E_CPU1_P3_TX_BUF_DN<15>")
		)
	)
	(footprint ""
		(layer "B.Cu")
		(at 449.79971 -423.935398 180)
		(property "Reference" "PR6618"
			(at 0 0 0)
			(layer "B.SilkS")
			(hide yes)
			(effects
				(font
					(size 1.27 1.27)
				)
				(justify mirror)
			)
		)
		(property "Value" ""
			(at 0 0 0)
			(layer "B.Fab")
			(effects
				(font
					(size 1.27 1.27)
				)
				(justify mirror)
			)
		)
		(duplicate_pad_numbers_are_jumpers no)
		(fp_line
			(start 0.7874 0.4064)
			(end 0.7874 -0.4064)
			(stroke
				(width 0.1524)
				(type default)
			)
			(layer "B.SilkS")
		)
		(fp_line
			(start 0.7874 -0.4064)
			(end -0.7874 -0.4064)
			(stroke
				(width 0.1524)
				(type default)
			)
			(layer "B.SilkS")
		)
		(fp_line
			(start -0.7874 0.4064)
			(end 0.7874 0.4064)
			(stroke
				(width 0.1524)
				(type default)
			)
			(layer "B.SilkS")
		)
		(fp_line
			(start -0.7874 -0.4064)
			(end -0.7874 0.4064)
			(stroke
				(width 0.1524)
				(type default)
			)
			(layer "B.SilkS")
		)
		(fp_line
			(start 0.67945 0.3048)
			(end 0.67945 -0.305054)
			(stroke
				(width 0.1)
				(type default)
			)
			(layer "B.Fab")
		)
		(fp_line
			(start 0.67945 -0.305054)
			(end 0.12065 -0.305054)
			(stroke
				(width 0.1)
				(type default)
			)
			(layer "B.Fab")
		)
		(fp_line
			(start 0.12065 0.3048)
			(end 0.67945 0.3048)
			(stroke
				(width 0.1)
				(type default)
			)
			(layer "B.Fab")
		)
		(fp_line
			(start 0.12065 0.2794)
			(end 0.12065 0.3048)
			(stroke
				(width 0.1)
				(type default)
			)
			(layer "B.Fab")
		)
		(fp_line
			(start 0.12065 -0.2794)
			(end -0.12065 -0.2794)
			(stroke
				(width 0.1)
				(type default)
			)
			(layer "B.Fab")
		)
		(fp_line
			(start 0.12065 -0.305054)
			(end 0.12065 -0.2794)
			(stroke
				(width 0.1)
				(type default)
			)
			(layer "B.Fab")
		)
		(fp_line
			(start -0.120396 0.3048)
			(end -0.120396 0.2794)
			(stroke
				(width 0.1)
				(type default)
			)
			(layer "B.Fab")
		)
		(fp_line
			(start -0.120396 0.2794)
			(end 0.12065 0.2794)
			(stroke
				(width 0.1)
				(type default)
			)
			(layer "B.Fab")
		)
		(fp_line
			(start -0.12065 -0.2794)
			(end -0.12065 -0.3048)
			(stroke
				(width 0.1)
				(type default)
			)
			(layer "B.Fab")
		)
		(fp_line
			(start -0.12065 -0.3048)
			(end -0.67945 -0.3048)
			(stroke
				(width 0.1)
				(type default)
			)
			(layer "B.Fab")
		)
		(fp_line
			(start -0.67945 0.3048)
			(end -0.120396 0.3048)
			(stroke
				(width 0.1)
				(type default)
			)
			(layer "B.Fab")
		)
		(fp_line
			(start -0.67945 -0.3048)
			(end -0.67945 0.3048)
			(stroke
				(width 0.1)
				(type default)
			)
			(layer "B.Fab")
		)
		(pad "1" smd circle
			(at 0.40005 0)
			(size 0 0)
			(layers "B.Cu" "B.Mask" "B.Paste")
			(net "P0V9_RETIMER_CPU0_TEMP1_R")
		)
		(pad "2" smd circle
			(at -0.40005 0)
			(size 0 0)
			(layers "B.Cu" "B.Mask" "B.Paste")
			(net "GND")
		)
	)
)
